# T6G (Grand Teton) — schematic netlist excerpt (pin names and nets, part order shuffled) for the footprints in the layout excerpt that follows; sources: Cadence DE-HDL packaged netlist, KiCad conversion of 04192023_DAF0TMB3IC0_F0TG_MB_C_brd_V02_OCP.brd

C2232  Q_CAP  22UF 4V 20% X6S  pkg C0402  page 69 : A = PVDDCR_CPU1_P0 ; B = GND
C2193  Q_CAP  22UF 4V 20% X6S  pkg C0402  page 69 : A = PVDDCR_CPU0_P0 ; B = GND

(kicad_pcb
	(version 20260206)
	(generator "pcbnew")
	(generator_version "10.0")
	(general
		(thickness 1.6)
		(legacy_teardrops no)
	)
	(paper "A4")
	(title_block
		(title "04192023_DAF0TMB3IC0_F0TG_MB_C_brd_V02_OCP.brd")
		(comment 1 "Grand Teton / footprints 5673-5674 of 8354")
	)
	(layers
		(0 "F.Cu" signal "TOP")
		(4 "In1.Cu" signal "GND")
		(6 "In2.Cu" signal "IN1")
		(8 "In3.Cu" signal "GND1")
		(10 "In4.Cu" signal "IN2")
		(12 "In5.Cu" signal "GND2")
		(14 "In6.Cu" signal "IN3")
		(16 "In7.Cu" signal "GND3")
		(18 "In8.Cu" signal "VCC")
		(20 "In9.Cu" signal "VCC1")
		(22 "In10.Cu" signal "GND4")
		(24 "In11.Cu" signal "IN4")
		(26 "In12.Cu" signal "GND5")
		(28 "In13.Cu" signal "IN5")
		(30 "In14.Cu" signal "GND6")
		(32 "In15.Cu" signal "IN6")
		(34 "In16.Cu" signal "GND7")
		(2 "B.Cu" signal "BOTTOM")
		(9 "F.Adhes" user "F.Adhesive")
		(11 "B.Adhes" user "B.Adhesive")
		(13 "F.Paste" user "Package Geometry/Pastemask Top")
		(15 "B.Paste" user "Package Geometry/Pastemask Bottom")
		(5 "F.SilkS" user "Ref Des/Silkscreen Top")
		(7 "B.SilkS" user "Ref Des/Silkscreen Bottom")
		(1 "F.Mask" user "Board Geometry/Soldermask Top")
		(3 "B.Mask" user "Board Geometry/Soldermask Bottom")
		(17 "Dwgs.User" user "User.Drawings")
		(19 "Cmts.User" user "User.Comments")
		(21 "Eco1.User" user "User.Eco1")
		(23 "Eco2.User" user "User.Eco2")
		(25 "Edge.Cuts" user "Board Geometry/Outline")
		(27 "Margin" user)
		(31 "F.CrtYd" user "Package Geometry/Place Bound Top")
		(29 "B.CrtYd" user "Package Geometry/Place Bound Bottom")
		(35 "F.Fab" user "Ref Des/Assembly Top")
		(33 "B.Fab" user "Ref Des/Assembly Bottom")
	)
	(footprint ""
		(layer "B.Cu")
		(at 367.995454 -268.41831)
		(property "Reference" "C2232"
			(at 0 0 0)
			(layer "B.SilkS")
			(hide yes)
			(effects
				(font
					(size 1.27 1.27)
				)
				(justify mirror)
			)
		)
		(property "Value" ""
			(at 0 0 0)
			(layer "B.Fab")
			(effects
				(font
					(size 1.27 1.27)
				)
				(justify mirror)
			)
		)
		(duplicate_pad_numbers_are_jumpers no)
		(fp_line
			(start -0.7874 -0.4064)
			(end -0.7874 0.4064)
			(stroke
				(width 0.1524)
				(type default)
			)
			(layer "B.SilkS")
		)
		(fp_line
			(start -0.7874 0.4064)
			(end 0.7874 0.4064)
			(stroke
				(width 0.1524)
				(type default)
			)
			(layer "B.SilkS")
		)
		(fp_line
			(start 0.7874 -0.4064)
			(end -0.7874 -0.4064)
			(stroke
				(width 0.1524)
				(type default)
			)
			(layer "B.SilkS")
		)
		(fp_line
			(start 0.7874 0.4064)
			(end 0.7874 -0.4064)
			(stroke
				(width 0.1524)
				(type default)
			)
			(layer "B.SilkS")
		)
		(fp_line
			(start -0.67945 -0.3048)
			(end -0.67945 0.3048)
			(stroke
				(width 0.1)
				(type default)
			)
			(layer "B.Fab")
		)
		(fp_line
			(start -0.67945 0.3048)
			(end -0.120396 0.3048)
			(stroke
				(width 0.1)
				(type default)
			)
			(layer "B.Fab")
		)
		(fp_line
			(start -0.12065 -0.3048)
			(end -0.67945 -0.3048)
			(stroke
				(width 0.1)
				(type default)
			)
			(layer "B.Fab")
		)
		(fp_line
			(start -0.12065 -0.2794)
			(end -0.12065 -0.3048)
			(stroke
				(width 0.1)
				(type default)
			)
			(layer "B.Fab")
		)
		(fp_line
			(start -0.120396 0.2794)
			(end 0.12065 0.2794)
			(stroke
				(width 0.1)
				(type default)
			)
			(layer "B.Fab")
		)
		(fp_line
			(start -0.120396 0.3048)
			(end -0.120396 0.2794)
			(stroke
				(width 0.1)
				(type default)
			)
			(layer "B.Fab")
		)
		(fp_line
			(start 0.12065 -0.305054)
			(end 0.12065 -0.2794)
			(stroke
				(width 0.1)
				(type default)
			)
			(layer "B.Fab")
		)
		(fp_line
			(start 0.12065 -0.2794)
			(end -0.12065 -0.2794)
			(stroke
				(width 0.1)
				(type default)
			)
			(layer "B.Fab")
		)
		(fp_line
			(start 0.12065 0.2794)
			(end 0.12065 0.3048)
			(stroke
				(width 0.1)
				(type default)
			)
			(layer "B.Fab")
		)
		(fp_line
			(start 0.12065 0.3048)
			(end 0.67945 0.3048)
			(stroke
				(width 0.1)
				(type default)
			)
			(layer "B.Fab")
		)
		(fp_line
			(start 0.67945 -0.305054)
			(end 0.12065 -0.305054)
			(stroke
				(width 0.1)
				(type default)
			)
			(layer "B.Fab")
		)
		(fp_line
			(start 0.67945 0.3048)
			(end 0.67945 -0.305054)
			(stroke
				(width 0.1)
				(type default)
			)
			(layer "B.Fab")
		)
		(pad "1" smd circle
			(at 0.40005 0 180)
			(size 0 0)
			(layers "B.Cu" "B.Mask" "B.Paste")
			(net "PVDDCR_CPU1_P0")
		)
		(pad "2" smd circle
			(at -0.40005 0 180)
			(size 0 0)
			(layers "B.Cu" "B.Mask" "B.Paste")
			(net "GND")
		)
	)
	(footprint ""
		(layer "B.Cu")
		(at 359.740454 -247.97131 90)
		(property "Reference" "C2193"
			(at 0 0 90)
			(layer "B.SilkS")
			(hide yes)
			(effects
				(font
					(size 1.27 1.27)
				)
				(justify mirror)
			)
		)
		(property "Value" ""
			(at 0 0 90)
			(layer "B.Fab")
			(effects
				(font
					(size 1.27 1.27)
				)
				(justify mirror)
			)
		)
		(duplicate_pad_numbers_are_jumpers no)
		(fp_line
			(start 0.7874 -0.4064)
			(end -0.7874 -0.4064)
			(stroke
				(width 0.1524)
				(type default)
			)
			(layer "B.SilkS")
		)
		(fp_line
			(start -0.7874 -0.4064)
			(end -0.7874 0.4064)
			(stroke
				(width 0.1524)
				(type default)
			)
			(layer "B.SilkS")
		)
		(fp_line
			(start 0.7874 0.4064)
			(end 0.7874 -0.4064)
			(stroke
				(width 0.1524)
				(type default)
			)
			(layer "B.SilkS")
		)
		(fp_line
			(start -0.7874 0.4064)
			(end 0.7874 0.4064)
			(stroke
				(width 0.1524)
				(type default)
			)
			(layer "B.SilkS")
		)
		(fp_line
			(start 0.67945 -0.305054)
			(end 0.12065 -0.305054)
			(stroke
				(width 0.1)
				(type default)
			)
			(layer "B.Fab")
		)
		(fp_line
			(start 0.12065 -0.305054)
			(end 0.12065 -0.2794)
			(stroke
				(width 0.1)
				(type default)
			)
			(layer "B.Fab")
		)
		(fp_line
			(start -0.12065 -0.3048)
			(end -0.67945 -0.3048)
			(stroke
				(width 0.1)
				(type default)
			)
			(layer "B.Fab")
		)
		(fp_line
			(start -0.67945 -0.3048)
			(end -0.67945 0.3048)
			(stroke
				(width 0.1)
				(type default)
			)
			(layer "B.Fab")
		)
		(fp_line
			(start 0.12065 -0.2794)
			(end -0.12065 -0.2794)
			(stroke
				(width 0.1)
				(type default)
			)
			(layer "B.Fab")
		)
		(fp_line
			(start -0.12065 -0.2794)
			(end -0.12065 -0.3048)
			(stroke
				(width 0.1)
				(type default)
			)
			(layer "B.Fab")
		)
		(fp_line
			(start 0.12065 0.2794)
			(end 0.12065 0.3048)
			(stroke
				(width 0.1)
				(type default)
			)
			(layer "B.Fab")
		)
		(fp_line
			(start -0.120396 0.2794)
			(end 0.12065 0.2794)
			(stroke
				(width 0.1)
				(type default)
			)
			(layer "B.Fab")
		)
		(fp_line
			(start 0.67945 0.3048)
			(end 0.67945 -0.305054)
			(stroke
				(width 0.1)
				(type default)
			)
			(layer "B.Fab")
		)
		(fp_line
			(start 0.12065 0.3048)
			(end 0.67945 0.3048)
			(stroke
				(width 0.1)
				(type default)
			)
			(layer "B.Fab")
		)
		(fp_line
			(start -0.120396 0.3048)
			(end -0.120396 0.2794)
			(stroke
				(width 0.1)
				(type default)
			)
			(layer "B.Fab")
		)
		(fp_line
			(start -0.67945 0.3048)
			(end -0.120396 0.3048)
			(stroke
				(width 0.1)
				(type default)
			)
			(layer "B.Fab")
		)
		(pad "1" smd circle
			(at 0.40005 0 270)
			(size 0 0)
			(layers "B.Cu" "B.Mask" "B.Paste")
			(net "PVDDCR_CPU0_P0")
		)
		(pad "2" smd circle
			(at -0.40005 0 270)
			(size 0 0)
			(layers "B.Cu" "B.Mask" "B.Paste")
			(net "GND")
		)
	)
)
